# S9S_MB_2U (Grand Teton) — schematic netlist excerpt (pin names and nets, part order shuffled) for the footprints in the layout excerpt that follows; sources: Cadence DE-HDL packaged netlist, KiCad conversion of 03242023_DA0F0TMBIJ0_F0T_Motherboard_J_brd_V01_OCP.brd

J6  SCONN288_ADR50017P087CC  SCONN288_ADR50017-P087CC IO  pkg DDR288S_1-1VXB  page 87
  VIN_BULK0  = P12V_S3_AUX_CPU0_NVDIMM
  RFU0  = TP_CHC_CPU0_DIMM2_FRU_0
  VIN_MGMT  = P3V3_AUX
  HSCL  = I3C_SPD_DDRABCD_CPU0_LVC1_SCL_5
  HSDA  = I3C_SPD_DDRABCD_CPU0_LVC1_SDA
  VSS0  = GND
  DQ0_A  = M_C_CPU0_SA_DQ<0>
  VSS1  = GND
  DQ1_A  = M_C_CPU0_SA_DQ<1>
  VSS2  = GND
  DQS0_A_T  = M_C_CPU0_SA_DQS_DP<0>
  DQS0_A_C  = M_C_CPU0_SA_DQS_DN<0>
  VSS3  = GND
  DQ4_A  = M_C_CPU0_SA_DQ<4>
  VSS4  = GND
  DQ5_A  = M_C_CPU0_SA_DQ<5>
  VSS5  = GND
  DQ8_A  = M_C_CPU0_SA_DQ<8>
  VSS6  = GND
  DQ9_A  = M_C_CPU0_SA_DQ<9>
  VSS7  = GND
  DQS1_A_T  = M_C_CPU0_SA_DQS_DP<1>
  DQS1_A_C  = M_C_CPU0_SA_DQS_DN<1>
  VSS8  = GND
  DQ12_A  = M_C_CPU0_SA_DQ<12>
  VSS9  = GND
  DQ13_A  = M_C_CPU0_SA_DQ<13>
  VSS10  = GND
  DQ16_A  = M_C_CPU0_SA_DQ<16>
  VSS11  = GND
  DQ17_A  = M_C_CPU0_SA_DQ<17>
  VSS12  = GND
  DQS2_A_T  = M_C_CPU0_SA_DQS_DP<2>
  DQS2_A_C  = M_C_CPU0_SA_DQS_DN<2>
  VSS13  = GND
  DQ20_A  = M_C_CPU0_SA_DQ<20>
  VSS14  = GND
  DQ21_A  = M_C_CPU0_SA_DQ<21>
  VSS15  = GND
  DQ24_A  = M_C_CPU0_SA_DQ<24>
  VSS16  = GND
  DQ25_A  = M_C_CPU0_SA_DQ<25>
  VSS17  = GND
  DQS3_A_T  = M_C_CPU0_SA_DQS_DP<3>
  DQS3_A_C  = M_C_CPU0_SA_DQS_DN<3>
  VSS18  = GND
  DQ28_A  = M_C_CPU0_SA_DQ<28>
  VSS19  = GND
  DQ29_A  = M_C_CPU0_SA_DQ<29>
  VSS20  = GND
  CB0_A  = M_C_CPU0_SA_CB<0>
  VSS21  = GND
  CB1_A  = M_C_CPU0_SA_CB<1>
  VSS22  = GND
  DQS4_A_T  = M_C_CPU0_SA_DQS_DP<4>
  DQS4_A_C  = M_C_CPU0_SA_DQS_DN<4>
  VSS23  = GND
  CB4_A  = M_C_CPU0_SA_CB<4>
  VSS24  = GND
  CB5_A  = M_C_CPU0_SA_CB<5>
  VSS25  = GND
  ALERT_N  = M_C_CPU0_ALERT_N
  VSS26  = GND
  CS0_A_N  = M_C_CPU0_SA_CS_N<2>
  VSS27  = GND
  CA0_A  = M_C_CPU0_SA_CA<0>
  VSS28  = GND
  CA2_A  = M_C_CPU0_SA_CA<2>
  VSS29  = GND
  CA4_A  = M_C_CPU0_SA_CA<4>
  VSS30  = GND
  CA6_A  = M_C_CPU0_SA_CA<6>
  VSS31  = GND
  PAR_A  = M_C_CPU0_SA_PAR
  VSS32  = GND
  CA0_B  = M_C_CPU0_SB_CA<0>
  VSS33  = GND
  CA2_B  = M_C_CPU0_SB_CA<2>
  VSS34  = GND
  CA4_B  = M_C_CPU0_SB_CA<4>
  VSS35  = GND
  CA6_B  = M_C_CPU0_SB_CA<6>
  VSS36  = GND
  CS0_B_N  = M_C_CPU0_SB_CS_N<2>
  VSS37  = GND
  \lbd||rsp_a_n\  = M_C_CPU0_SA_RSP<1>
  \lbs||rsp_b_n\  = M_C_CPU0_SB_RSP<1>
  VSS38  = GND
  CB4_B  = M_C_CPU0_SB_CB<4>
  VSS39  = GND
  CB5_B  = M_C_CPU0_SB_CB<5>
  VSS40  = GND
  \dqs9_b_t||tdqs9_b_t||dbi4_b_n\  = M_C_CPU0_SB_DQS_DP<9>
  \dqs9_b_c||tdqs9_b_c\  = M_C_CPU0_SB_DQS_DN<9>
  VSS41  = GND
  CB0_B  = M_C_CPU0_SB_CB<0>
  VSS42  = GND
  CB1_B  = M_C_CPU0_SB_CB<1>
  VSS43  = GND
  DQ0_B  = M_C_CPU0_SB_DQ<0>
  VSS44  = GND
  DQ1_B  = M_C_CPU0_SB_DQ<1>
  VSS45  = GND
  DQS0_B_T  = M_C_CPU0_SB_DQS_DP<0>
  DQS0_B_C  = M_C_CPU0_SB_DQS_DN<0>
  VSS46  = GND
  DQ4_B  = M_C_CPU0_SB_DQ<4>
  VSS47  = GND
  DQ5_B  = M_C_CPU0_SB_DQ<5>
  VSS48  = GND
  DQ8_B  = M_C_CPU0_SB_DQ<8>
  VSS49  = GND
  DQ9_B  = M_C_CPU0_SB_DQ<9>
  VSS50  = GND
  DQS1_B_T  = M_C_CPU0_SB_DQS_DP<1>
  DQS1_B_C  = M_C_CPU0_SB_DQS_DN<1>
  VSS51  = GND
  DQ12_B  = M_C_CPU0_SB_DQ<12>
  VSS52  = GND
  DQ13_B  = M_C_CPU0_SB_DQ<13>
  VSS53  = GND
  DQ16_B  = M_C_CPU0_SB_DQ<16>
  VSS54  = GND
  DQ17_B  = M_C_CPU0_SB_DQ<17>
  VSS55  = GND
  DQS2_B_T  = M_C_CPU0_SB_DQS_DP<2>
  DQS2_B_C  = M_C_CPU0_SB_DQS_DN<2>
  VSS56  = GND
  DQ20_B  = M_C_CPU0_SB_DQ<20>
  VSS57  = GND
  DQ21_B  = M_C_CPU0_SB_DQ<21>
  VSS58  = GND
  DQ24_B  = M_C_CPU0_SB_DQ<24>
  VSS59  = GND
  DQ25_B  = M_C_CPU0_SB_DQ<25>
  VSS60  = GND
  DQS3_B_T  = M_C_CPU0_SB_DQS_DP<3>
  DQS3_B_C  = M_C_CPU0_SB_DQS_DN<3>
  VSS61  = GND
  DQ28_B  = M_C_CPU0_SB_DQ<28>
  VSS62  = GND
  DQ29_B  = M_C_CPU0_SB_DQ<29>
  VSS63  = GND
  RFU1  = TP_CHC_CPU0_DIMM2_FRU_1
  VIN_BULK1  = P12V_S3_AUX_CPU0_NVDIMM
  VIN_BULK2  = P12V_S3_AUX_CPU0_NVDIMM
  \pwr_good||fail_n\  = PWRGD_CHC_CPU0_DIMM2
  HSA  = PD_CHC_CPU0_DIMM2_SAA
  RFU2  = TP_CHC_CPU0_DIMM2_FRU_2
  RFU3  = TP_CHC_CPU0_DIMM2_FRU_3
  VSS64  = GND
  DQ2_A  = M_C_CPU0_SA_DQ<2>
  VSS65  = GND
  DQ3_A  = M_C_CPU0_SA_DQ<3>
  VSS66  = GND
  \dqs5_a_c||tdqs5_a_c||dqs5_a_t||tdqs5_a_t\  = M_C_CPU0_SA_DQS_DN<5>
  \dqs5_a_t||tdqs5_a_t\  = M_C_CPU0_SA_DQS_DP<5>
  VSS67  = GND
  DQ6_A  = M_C_CPU0_SA_DQ<6>
  VSS68  = GND
  DQ7_A  = M_C_CPU0_SA_DQ<7>
  VSS69  = GND
  DQ10_A  = M_C_CPU0_SA_DQ<10>
  VSS70  = GND
  DQ11_A  = M_C_CPU0_SA_DQ<11>
  VSS71  = GND
  \dqs6_a_c||tdqs6_a_c||dqs6_a_t||tdqs6_a_t\  = M_C_CPU0_SA_DQS_DN<6>
  \dqs6_a_t||tdqs6_a_t\  = M_C_CPU0_SA_DQS_DP<6>
  VSS72  = GND
  DQ14_A  = M_C_CPU0_SA_DQ<14>
  VSS73  = GND
  DQ15_A  = M_C_CPU0_SA_DQ<15>
  VSS74  = GND
  DQ18_A  = M_C_CPU0_SA_DQ<18>
  VSS75  = GND
  DQ19_A  = M_C_CPU0_SA_DQ<19>
  VSS76  = GND
  \dqs7_a_c||tdqs7_a_c\  = M_C_CPU0_SA_DQS_DN<7>
  \dqs7_a_t||tdqs7_a_t\  = M_C_CPU0_SA_DQS_DP<7>
  VSS77  = GND
  DQ22_A  = M_C_CPU0_SA_DQ<22>
  VSS78  = GND
  DQ23_A  = M_C_CPU0_SA_DQ<23>
  VSS79  = GND
  DQ26_A  = M_C_CPU0_SA_DQ<26>
  VSS80  = GND
  DQ27_A  = M_C_CPU0_SA_DQ<27>
  VSS81  = GND
  \dqs8_a_c||tdqs8_a_c\  = M_C_CPU0_SA_DQS_DN<8>
  \dqs8_a_t||tdqs8_a_t\  = M_C_CPU0_SA_DQS_DP<8>
  VSS82  = GND
  DQ30_A  = M_C_CPU0_SA_DQ<30>
  VSS83  = GND
  DQ31_A  = M_C_CPU0_SA_DQ<31>
  VSS84  = GND
  CB2_A  = M_C_CPU0_SA_CB<2>
  VSS85  = GND
  CB3_A  = M_C_CPU0_SA_CB<3>
  VSS86  = GND
  \dqs9_a_c||tdqs9_a_c\  = M_C_CPU0_SA_DQS_DN<9>
  \dqs9_a_t||tdqs9_a_t\  = M_C_CPU0_SA_DQS_DP<9>
  VSS87  = GND
  CB6_A  = M_C_CPU0_SA_CB<6>
  VSS88  = GND
  CB7_A  = M_C_CPU0_SA_CB<7>
  VSS89  = GND
  RESET_N  = RST_M_CD_CPU0_FPGA_N
  VSS90  = GND
  CS1_A_N  = M_C_CPU0_SA_CS_N<3>
  VSS91  = GND
  CA1_A  = M_C_CPU0_SA_CA<1>
  VSS92  = GND
  CA3_A  = M_C_CPU0_SA_CA<3>
  VSS93  = GND
  CA5_A  = M_C_CPU0_SA_CA<5>
  VSS94  = GND
  CK_T  = M_C_CPU0_CLK_DP<1>
  CK_C  = M_C_CPU0_CLK_DN<1>
  VSS95  = GND
  RFU4  = TP_CHC_CPU0_DIMM2_FRU_4
  CA1_B  = M_C_CPU0_SB_CA<1>
  VSS96  = GND
  CA3_B  = M_C_CPU0_SB_CA<3>
  VSS97  = GND
  CA5_B  = M_C_CPU0_SB_CA<5>
  VSS98  = GND
  PAR_B  = M_C_CPU0_SB_PAR
  VSS99  = GND
  CS1_B_N  = M_C_CPU0_SB_CS_N<3>
  VSS100  = GND
  RFU5  = TP_CHC_CPU0_DIMM2_FRU_5
  RFU6  = TP_CHC_CPU0_DIMM2_FRU_6
  VSS101  = GND
  CB6_B  = M_C_CPU0_SB_CB<6>
  VSS102  = GND
  CB7_B  = M_C_CPU0_SB_CB<7>
  VSS103  = GND
  DQS4_B_C  = M_C_CPU0_SB_DQS_DN<4>
  DQS4_B_T  = M_C_CPU0_SB_DQS_DP<4>
  VSS104  = GND
  CB2_B  = M_C_CPU0_SB_CB<2>
  VSS105  = GND
  CB3_B  = M_C_CPU0_SB_CB<3>
  VSS106  = GND
  DQ2_B  = M_C_CPU0_SB_DQ<2>
  VSS107  = GND
  DQ3_B  = M_C_CPU0_SB_DQ<3>
  VSS108  = GND
  \dqs5_b_c||tdqs5_b_c\  = M_C_CPU0_SB_DQS_DN<5>
  \dqs5_b_t||tdqs5_b_t\  = M_C_CPU0_SB_DQS_DP<5>
  VSS109  = GND
  DQ6_B  = M_C_CPU0_SB_DQ<6>
  VSS110  = GND
  DQ7_B  = M_C_CPU0_SB_DQ<7>
  VSS111  = GND
  DQ10_B  = M_C_CPU0_SB_DQ<10>
  VSS112  = GND
  DQ11_B  = M_C_CPU0_SB_DQ<11>
  VSS113  = GND
  \dqs6_b_c||tdqs6_b_c\  = M_C_CPU0_SB_DQS_DN<6>
  \dqs6_b_t||tdqs6_b_t\  = M_C_CPU0_SB_DQS_DP<6>
  VSS114  = GND
  DQ14_B  = M_C_CPU0_SB_DQ<14>
  VSS115  = GND
  DQ15_B  = M_C_CPU0_SB_DQ<15>
  VSS116  = GND
  DQ18_B  = M_C_CPU0_SB_DQ<18>
  VSS117  = GND
  DQ19_B  = M_C_CPU0_SB_DQ<19>
  VSS118  = GND
  \dqs7_b_c||tdqs7_b_c\  = M_C_CPU0_SB_DQS_DN<7>
  \dqs7_b_t||tdqs7_b_t\  = M_C_CPU0_SB_DQS_DP<7>
  VSS119  = GND
  DQ22_B  = M_C_CPU0_SB_DQ<22>
  VSS120  = GND
  DQ23_B  = M_C_CPU0_SB_DQ<23>
  VSS121  = GND
  DQ26_B  = M_C_CPU0_SB_DQ<26>
  VSS122  = GND
  DQ27_B  = M_C_CPU0_SB_DQ<27>
  VSS123  = GND
  \dqs8_b_c||tdqs8_b_c\  = M_C_CPU0_SB_DQS_DN<8>
  \dqs8_b_t||tdqs8_b_t\  = M_C_CPU0_SB_DQS_DP<8>
  VSS124  = GND
  DQ30_B  = M_C_CPU0_SB_DQ<30>
  VSS125  = GND
  DQ31_B  = M_C_CPU0_SB_DQ<31>
  VSS126  = GND
  G1  = GND
  G2  = GND
  G3  = GND

(kicad_pcb
	(version 20260206)
	(generator "pcbnew")
	(generator_version "10.0")
	(general
		(thickness 1.6)
		(legacy_teardrops no)
	)
	(paper "A4")
	(title_block
		(title "03242023_DA0F0TMBIJ0_F0T_Motherboard_J_brd_V01_OCP.brd")
		(comment 1 "Grand Teton / footprint 3553 of 6105 (J6), pads 183-228 of 291")
	)
	(layers
		(0 "F.Cu" signal "TOP")
		(4 "In1.Cu" signal "GND")
		(6 "In2.Cu" signal "IN1")
		(8 "In3.Cu" signal "GND1")
		(10 "In4.Cu" signal "IN2")
		(12 "In5.Cu" signal "GND2")
		(14 "In6.Cu" signal "IN3")
		(16 "In7.Cu" signal "GND3")
		(18 "In8.Cu" signal "VCC")
		(20 "In9.Cu" signal "VCC1")
		(22 "In10.Cu" signal "GND4")
		(24 "In11.Cu" signal "IN4")
		(26 "In12.Cu" signal "GND5")
		(28 "In13.Cu" signal "IN5")
		(30 "In14.Cu" signal "GND6")
		(32 "In15.Cu" signal "IN6")
		(34 "In16.Cu" signal "GND7")
		(2 "B.Cu" signal "BOTTOM")
		(9 "F.Adhes" user "F.Adhesive")
		(11 "B.Adhes" user "B.Adhesive")
		(13 "F.Paste" user "Package Geometry/Pastemask Top")
		(15 "B.Paste" user "Package Geometry/Pastemask Bottom")
		(5 "F.SilkS" user "Ref Des/Silkscreen Top")
		(7 "B.SilkS" user "Ref Des/Silkscreen Bottom")
		(1 "F.Mask" user "Board Geometry/Soldermask Top")
		(3 "B.Mask" user "Board Geometry/Soldermask Bottom")
		(17 "Dwgs.User" user "User.Drawings")
		(19 "Cmts.User" user "User.Comments")
		(21 "Eco1.User" user "User.Eco1")
		(23 "Eco2.User" user "User.Eco2")
		(25 "Edge.Cuts" user "Board Geometry/Outline")
		(27 "Margin" user)
		(31 "F.CrtYd" user "Package Geometry/Place Bound Top")
		(29 "B.CrtYd" user "Package Geometry/Place Bound Bottom")
		(35 "F.Fab" user "Ref Des/Assembly Top")
		(33 "B.Fab" user "Ref Des/Assembly Bottom")
	)
	(footprint ""
		(layer "F.Cu")
		(at 280.761948 -258.091686)
		(property "Reference" "J6"
			(at -3.683 -81.702148 0)
			(unlocked yes)
			(layer "F.SilkS")
			(effects
				(font
					(size 0.7874 0.5842)
					(thickness 0.1524)
				)
				(justify left)
			)
		)
		(property "Value" ""
			(at 0 0 0)
			(layer "F.Fab")
			(effects
				(font
					(size 1.27 1.27)
				)
			)
		)
		(duplicate_pad_numbers_are_jumpers no)
		(pad "183" smd rect
			(at 2.050034 -31.025084 270)
			(size 0.519938 1.4986)
			(layers "F.Cu" "F.Mask" "F.Paste")
			(net "M_C_CPU0_SA_DQ<23>")
		)
		(pad "184" smd rect
			(at 2.050034 -30.174946 270)
			(size 0.519938 1.4986)
			(layers "F.Cu" "F.Mask" "F.Paste")
			(net "GND")
		)
		(pad "185" smd rect
			(at 2.050034 -29.325062 270)
			(size 0.519938 1.4986)
			(layers "F.Cu" "F.Mask" "F.Paste")
			(net "M_C_CPU0_SA_DQ<26>")
		)
		(pad "186" smd rect
			(at 2.050034 -28.474924 270)
			(size 0.519938 1.4986)
			(layers "F.Cu" "F.Mask" "F.Paste")
			(net "GND")
		)
		(pad "187" smd rect
			(at 2.050034 -27.62504 270)
			(size 0.519938 1.4986)
			(layers "F.Cu" "F.Mask" "F.Paste")
			(net "M_C_CPU0_SA_DQ<27>")
		)
		(pad "188" smd rect
			(at 2.050034 -26.774902 270)
			(size 0.519938 1.4986)
			(layers "F.Cu" "F.Mask" "F.Paste")
			(net "GND")
		)
		(pad "189" smd rect
			(at 2.050034 -25.925018 270)
			(size 0.519938 1.4986)
			(layers "F.Cu" "F.Mask" "F.Paste")
			(net "M_C_CPU0_SA_DQS_DN<8>")
		)
		(pad "190" smd rect
			(at 2.050034 -25.07488 270)
			(size 0.519938 1.4986)
			(layers "F.Cu" "F.Mask" "F.Paste")
			(net "M_C_CPU0_SA_DQS_DP<8>")
		)
		(pad "191" smd rect
			(at 2.050034 -24.224996 270)
			(size 0.519938 1.4986)
			(layers "F.Cu" "F.Mask" "F.Paste")
			(net "GND")
		)
		(pad "192" smd rect
			(at 2.050034 -23.375112 270)
			(size 0.519938 1.4986)
			(layers "F.Cu" "F.Mask" "F.Paste")
			(net "M_C_CPU0_SA_DQ<30>")
		)
		(pad "193" smd rect
			(at 2.050034 -22.524974 270)
			(size 0.519938 1.4986)
			(layers "F.Cu" "F.Mask" "F.Paste")
			(net "GND")
		)
		(pad "194" smd rect
			(at 2.050034 -21.67509 270)
			(size 0.519938 1.4986)
			(layers "F.Cu" "F.Mask" "F.Paste")
			(net "M_C_CPU0_SA_DQ<31>")
		)
		(pad "195" smd rect
			(at 2.050034 -20.824952 270)
			(size 0.519938 1.4986)
			(layers "F.Cu" "F.Mask" "F.Paste")
			(net "GND")
		)
		(pad "196" smd rect
			(at 2.050034 -19.975068 270)
			(size 0.519938 1.4986)
			(layers "F.Cu" "F.Mask" "F.Paste")
			(net "M_C_CPU0_SA_CB<2>")
		)
		(pad "197" smd rect
			(at 2.050034 -19.12493 270)
			(size 0.519938 1.4986)
			(layers "F.Cu" "F.Mask" "F.Paste")
			(net "GND")
		)
		(pad "198" smd rect
			(at 2.050034 -18.275046 270)
			(size 0.519938 1.4986)
			(layers "F.Cu" "F.Mask" "F.Paste")
			(net "M_C_CPU0_SA_CB<3>")
		)
		(pad "199" smd rect
			(at 2.050034 -17.424908 270)
			(size 0.519938 1.4986)
			(layers "F.Cu" "F.Mask" "F.Paste")
			(net "GND")
		)
		(pad "200" smd rect
			(at 2.050034 -16.575024 270)
			(size 0.519938 1.4986)
			(layers "F.Cu" "F.Mask" "F.Paste")
			(net "M_C_CPU0_SA_DQS_DN<9>")
		)
		(pad "201" smd rect
			(at 2.050034 -15.724886 270)
			(size 0.519938 1.4986)
			(layers "F.Cu" "F.Mask" "F.Paste")
			(net "M_C_CPU0_SA_DQS_DP<9>")
		)
		(pad "202" smd rect
			(at 2.050034 -14.875002 270)
			(size 0.519938 1.4986)
			(layers "F.Cu" "F.Mask" "F.Paste")
			(net "GND")
		)
		(pad "203" smd rect
			(at 2.050034 -14.025118 270)
			(size 0.519938 1.4986)
			(layers "F.Cu" "F.Mask" "F.Paste")
			(net "M_C_CPU0_SA_CB<6>")
		)
		(pad "204" smd rect
			(at 2.050034 -13.17498 270)
			(size 0.519938 1.4986)
			(layers "F.Cu" "F.Mask" "F.Paste")
			(net "GND")
		)
		(pad "205" smd rect
			(at 2.050034 -12.325096 270)
			(size 0.519938 1.4986)
			(layers "F.Cu" "F.Mask" "F.Paste")
			(net "M_C_CPU0_SA_CB<7>")
		)
		(pad "206" smd rect
			(at 2.050034 -11.474958 270)
			(size 0.519938 1.4986)
			(layers "F.Cu" "F.Mask" "F.Paste")
			(net "GND")
		)
		(pad "207" smd rect
			(at 2.050034 -10.625074 270)
			(size 0.519938 1.4986)
			(layers "F.Cu" "F.Mask" "F.Paste")
			(net "RST_M_CD_CPU0_FPGA_N")
		)
		(pad "208" smd rect
			(at 2.050034 -9.774936 270)
			(size 0.519938 1.4986)
			(layers "F.Cu" "F.Mask" "F.Paste")
			(net "GND")
		)
		(pad "209" smd rect
			(at 2.050034 -8.925052 270)
			(size 0.519938 1.4986)
			(layers "F.Cu" "F.Mask" "F.Paste")
			(net "M_C_CPU0_SA_CS_N<3>")
		)
		(pad "210" smd rect
			(at 2.050034 -8.074914 270)
			(size 0.519938 1.4986)
			(layers "F.Cu" "F.Mask" "F.Paste")
			(net "GND")
		)
		(pad "211" smd rect
			(at 2.050034 -7.22503 270)
			(size 0.519938 1.4986)
			(layers "F.Cu" "F.Mask" "F.Paste")
			(net "M_C_CPU0_SA_CA<1>")
		)
		(pad "212" smd rect
			(at 2.050034 -6.374892 270)
			(size 0.519938 1.4986)
			(layers "F.Cu" "F.Mask" "F.Paste")
			(net "GND")
		)
		(pad "213" smd rect
			(at 2.050034 -5.525008 270)
			(size 0.519938 1.4986)
			(layers "F.Cu" "F.Mask" "F.Paste")
			(net "M_C_CPU0_SA_CA<3>")
		)
		(pad "214" smd rect
			(at 2.050034 -4.675124 270)
			(size 0.519938 1.4986)
			(layers "F.Cu" "F.Mask" "F.Paste")
			(net "GND")
		)
		(pad "215" smd rect
			(at 2.050034 -3.824986 270)
			(size 0.519938 1.4986)
			(layers "F.Cu" "F.Mask" "F.Paste")
			(net "M_C_CPU0_SA_CA<5>")
		)
		(pad "216" smd rect
			(at 2.050034 -2.975102 270)
			(size 0.519938 1.4986)
			(layers "F.Cu" "F.Mask" "F.Paste")
			(net "GND")
		)
		(pad "217" smd rect
			(at 2.050034 -2.124964 270)
			(size 0.519938 1.4986)
			(layers "F.Cu" "F.Mask" "F.Paste")
			(net "M_C_CPU0_CLK_DP<1>")
		)
		(pad "218" smd rect
			(at 2.050034 -1.27508 270)
			(size 0.519938 1.4986)
			(layers "F.Cu" "F.Mask" "F.Paste")
			(net "M_C_CPU0_CLK_DN<1>")
		)
		(pad "219" smd rect
			(at 2.050034 -0.424942 270)
			(size 0.519938 1.4986)
			(layers "F.Cu" "F.Mask" "F.Paste")
			(net "GND")
		)
		(pad "220" smd rect
			(at 2.050034 5.525008 270)
			(size 0.519938 1.4986)
			(layers "F.Cu" "F.Mask" "F.Paste")
			(net "TP_CHC_CPU0_DIMM2_FRU_4")
		)
		(pad "221" smd rect
			(at 2.050034 6.374892 270)
			(size 0.519938 1.4986)
			(layers "F.Cu" "F.Mask" "F.Paste")
			(net "M_C_CPU0_SB_CA<1>")
		)
		(pad "222" smd rect
			(at 2.050034 7.22503 270)
			(size 0.519938 1.4986)
			(layers "F.Cu" "F.Mask" "F.Paste")
			(net "GND")
		)
		(pad "223" smd rect
			(at 2.050034 8.074914 270)
			(size 0.519938 1.4986)
			(layers "F.Cu" "F.Mask" "F.Paste")
			(net "M_C_CPU0_SB_CA<3>")
		)
		(pad "224" smd rect
			(at 2.050034 8.925052 270)
			(size 0.519938 1.4986)
			(layers "F.Cu" "F.Mask" "F.Paste")
			(net "GND")
		)
		(pad "225" smd rect
			(at 2.050034 9.774936 270)
			(size 0.519938 1.4986)
			(layers "F.Cu" "F.Mask" "F.Paste")
			(net "M_C_CPU0_SB_CA<5>")
		)
		(pad "226" smd rect
			(at 2.050034 10.625074 270)
			(size 0.519938 1.4986)
			(layers "F.Cu" "F.Mask" "F.Paste")
			(net "GND")
		)
		(pad "227" smd rect
			(at 2.050034 11.474958 270)
			(size 0.519938 1.4986)
			(layers "F.Cu" "F.Mask" "F.Paste")
			(net "M_C_CPU0_SB_PAR")
		)
		(pad "228" smd rect
			(at 2.050034 12.325096 270)
			(size 0.519938 1.4986)
			(layers "F.Cu" "F.Mask" "F.Paste")
			(net "GND")
		)
	)
)
